FILE_TYPE = CONNECTIVITY;
{Allegro Design Entry HDL 17.2-2016 S081 (4005846) 1/11/2022}
"PAGE_NUMBER" = 119;
0"NC";
END.
